# S9S_MB_2U (Grand Teton) — schematic netlist excerpt (pin names and nets, part order shuffled) for the footprints in the layout excerpt that follows; sources: Cadence DE-HDL packaged netlist, KiCad conversion of 03242023_DA0F0TMBIJ0_F0T_Motherboard_J_brd_V01_OCP.brd

PC501  Q_CAP  2.2UF 10V 10% X6S  pkg C0402  page 287 : A = PVCCIN_CPU1_VDD6 ; B = GND
C1863  Q_CAP  0.1UF 25V 10% X7R  pkg 0402  page 166 : A = P3V3_AUX ; B = GND

(kicad_pcb
	(version 20260206)
	(generator "pcbnew")
	(generator_version "10.0")
	(general
		(thickness 1.6)
		(legacy_teardrops no)
	)
	(paper "A4")
	(title_block
		(title "03242023_DA0F0TMBIJ0_F0T_Motherboard_J_brd_V01_OCP.brd")
		(comment 1 "Grand Teton / footprints 291-292 of 6105")
	)
	(layers
		(0 "F.Cu" signal "TOP")
		(4 "In1.Cu" signal "GND")
		(6 "In2.Cu" signal "IN1")
		(8 "In3.Cu" signal "GND1")
		(10 "In4.Cu" signal "IN2")
		(12 "In5.Cu" signal "GND2")
		(14 "In6.Cu" signal "IN3")
		(16 "In7.Cu" signal "GND3")
		(18 "In8.Cu" signal "VCC")
		(20 "In9.Cu" signal "VCC1")
		(22 "In10.Cu" signal "GND4")
		(24 "In11.Cu" signal "IN4")
		(26 "In12.Cu" signal "GND5")
		(28 "In13.Cu" signal "IN5")
		(30 "In14.Cu" signal "GND6")
		(32 "In15.Cu" signal "IN6")
		(34 "In16.Cu" signal "GND7")
		(2 "B.Cu" signal "BOTTOM")
		(9 "F.Adhes" user "F.Adhesive")
		(11 "B.Adhes" user "B.Adhesive")
		(13 "F.Paste" user "Package Geometry/Pastemask Top")
		(15 "B.Paste" user "Package Geometry/Pastemask Bottom")
		(5 "F.SilkS" user "Ref Des/Silkscreen Top")
		(7 "B.SilkS" user "Ref Des/Silkscreen Bottom")
		(1 "F.Mask" user "Board Geometry/Soldermask Top")
		(3 "B.Mask" user "Board Geometry/Soldermask Bottom")
		(17 "Dwgs.User" user "User.Drawings")
		(19 "Cmts.User" user "User.Comments")
		(21 "Eco1.User" user "User.Eco1")
		(23 "Eco2.User" user "User.Eco2")
		(25 "Edge.Cuts" user "Board Geometry/Outline")
		(27 "Margin" user)
		(31 "F.CrtYd" user "Package Geometry/Place Bound Top")
		(29 "B.CrtYd" user "Package Geometry/Place Bound Bottom")
		(35 "F.Fab" user "Ref Des/Assembly Top")
		(33 "B.Fab" user "Ref Des/Assembly Bottom")
	)
	(footprint ""
		(layer "F.Cu")
		(at 24.580596 -388.008876 -90)
		(property "Reference" "C1863"
			(at 0 0 270)
			(layer "F.SilkS")
			(hide yes)
			(effects
				(font
					(size 1.27 1.27)
				)
			)
		)
		(property "Value" ""
			(at 0 0 270)
			(layer "F.Fab")
			(effects
				(font
					(size 1.27 1.27)
				)
			)
		)
		(duplicate_pad_numbers_are_jumpers no)
		(fp_line
			(start -0.7874 0.4064)
			(end -0.7874 -0.4064)
			(stroke
				(width 0.1524)
				(type default)
			)
			(layer "F.SilkS")
		)
		(fp_line
			(start 0.7874 0.4064)
			(end -0.7874 0.4064)
			(stroke
				(width 0.1524)
				(type default)
			)
			(layer "F.SilkS")
		)
		(fp_line
			(start -0.7874 -0.4064)
			(end 0.7874 -0.4064)
			(stroke
				(width 0.1524)
				(type default)
			)
			(layer "F.SilkS")
		)
		(fp_line
			(start 0.7874 -0.4064)
			(end 0.7874 0.4064)
			(stroke
				(width 0.1524)
				(type default)
			)
			(layer "F.SilkS")
		)
		(fp_line
			(start -0.67945 0.3048)
			(end -0.67945 -0.305054)
			(stroke
				(width 0.1)
				(type default)
			)
			(layer "F.Fab")
		)
		(fp_line
			(start -0.12065 0.3048)
			(end -0.67945 0.3048)
			(stroke
				(width 0.1)
				(type default)
			)
			(layer "F.Fab")
		)
		(fp_line
			(start 0.120396 0.3048)
			(end 0.120396 0.2794)
			(stroke
				(width 0.1)
				(type default)
			)
			(layer "F.Fab")
		)
		(fp_line
			(start 0.67945 0.3048)
			(end 0.120396 0.3048)
			(stroke
				(width 0.1)
				(type default)
			)
			(layer "F.Fab")
		)
		(fp_line
			(start -0.12065 0.2794)
			(end -0.12065 0.3048)
			(stroke
				(width 0.1)
				(type default)
			)
			(layer "F.Fab")
		)
		(fp_line
			(start 0.120396 0.2794)
			(end -0.12065 0.2794)
			(stroke
				(width 0.1)
				(type default)
			)
			(layer "F.Fab")
		)
		(fp_line
			(start -0.12065 -0.2794)
			(end 0.12065 -0.2794)
			(stroke
				(width 0.1)
				(type default)
			)
			(layer "F.Fab")
		)
		(fp_line
			(start 0.12065 -0.2794)
			(end 0.12065 -0.3048)
			(stroke
				(width 0.1)
				(type default)
			)
			(layer "F.Fab")
		)
		(fp_line
			(start 0.12065 -0.3048)
			(end 0.67945 -0.3048)
			(stroke
				(width 0.1)
				(type default)
			)
			(layer "F.Fab")
		)
		(fp_line
			(start 0.67945 -0.3048)
			(end 0.67945 0.3048)
			(stroke
				(width 0.1)
				(type default)
			)
			(layer "F.Fab")
		)
		(fp_line
			(start -0.67945 -0.305054)
			(end -0.12065 -0.305054)
			(stroke
				(width 0.1)
				(type default)
			)
			(layer "F.Fab")
		)
		(fp_line
			(start -0.12065 -0.305054)
			(end -0.12065 -0.2794)
			(stroke
				(width 0.1)
				(type default)
			)
			(layer "F.Fab")
		)
		(pad "1" smd circle
			(at -0.40005 0 270)
			(size 0 0)
			(layers "F.Cu" "F.Mask" "F.Paste")
			(net "P3V3_AUX")
		)
		(pad "2" smd circle
			(at 0.40005 0 270)
			(size 0 0)
			(layers "F.Cu" "F.Mask" "F.Paste")
			(net "GND")
		)
	)
	(footprint ""
		(layer "F.Cu")
		(at 85.260942 -339.738462 90)
		(property "Reference" "PC501"
			(at 0 0 90)
			(layer "F.SilkS")
			(hide yes)
			(effects
				(font
					(size 1.27 1.27)
				)
			)
		)
		(property "Value" ""
			(at 0 0 90)
			(layer "F.Fab")
			(effects
				(font
					(size 1.27 1.27)
				)
			)
		)
		(duplicate_pad_numbers_are_jumpers no)
		(fp_line
			(start 0.7874 -0.4064)
			(end 0.7874 0.4064)
			(stroke
				(width 0.1524)
				(type default)
			)
			(layer "F.SilkS")
		)
		(fp_line
			(start -0.7874 -0.4064)
			(end 0.7874 -0.4064)
			(stroke
				(width 0.1524)
				(type default)
			)
			(layer "F.SilkS")
		)
		(fp_line
			(start 0.7874 0.4064)
			(end -0.7874 0.4064)
			(stroke
				(width 0.1524)
				(type default)
			)
			(layer "F.SilkS")
		)
		(fp_line
			(start -0.7874 0.4064)
			(end -0.7874 -0.4064)
			(stroke
				(width 0.1524)
				(type default)
			)
			(layer "F.SilkS")
		)
		(fp_line
			(start -0.12065 -0.305054)
			(end -0.12065 -0.2794)
			(stroke
				(width 0.1)
				(type default)
			)
			(layer "F.Fab")
		)
		(fp_line
			(start -0.67945 -0.305054)
			(end -0.12065 -0.305054)
			(stroke
				(width 0.1)
				(type default)
			)
			(layer "F.Fab")
		)
		(fp_line
			(start 0.67945 -0.3048)
			(end 0.67945 0.3048)
			(stroke
				(width 0.1)
				(type default)
			)
			(layer "F.Fab")
		)
		(fp_line
			(start 0.12065 -0.3048)
			(end 0.67945 -0.3048)
			(stroke
				(width 0.1)
				(type default)
			)
			(layer "F.Fab")
		)
		(fp_line
			(start 0.12065 -0.2794)
			(end 0.12065 -0.3048)
			(stroke
				(width 0.1)
				(type default)
			)
			(layer "F.Fab")
		)
		(fp_line
			(start -0.12065 -0.2794)
			(end 0.12065 -0.2794)
			(stroke
				(width 0.1)
				(type default)
			)
			(layer "F.Fab")
		)
		(fp_line
			(start 0.120396 0.2794)
			(end -0.12065 0.2794)
			(stroke
				(width 0.1)
				(type default)
			)
			(layer "F.Fab")
		)
		(fp_line
			(start -0.12065 0.2794)
			(end -0.12065 0.3048)
			(stroke
				(width 0.1)
				(type default)
			)
			(layer "F.Fab")
		)
		(fp_line
			(start 0.67945 0.3048)
			(end 0.120396 0.3048)
			(stroke
				(width 0.1)
				(type default)
			)
			(layer "F.Fab")
		)
		(fp_line
			(start 0.120396 0.3048)
			(end 0.120396 0.2794)
			(stroke
				(width 0.1)
				(type default)
			)
			(layer "F.Fab")
		)
		(fp_line
			(start -0.12065 0.3048)
			(end -0.67945 0.3048)
			(stroke
				(width 0.1)
				(type default)
			)
			(layer "F.Fab")
		)
		(fp_line
			(start -0.67945 0.3048)
			(end -0.67945 -0.305054)
			(stroke
				(width 0.1)
				(type default)
			)
			(layer "F.Fab")
		)
		(pad "1" smd circle
			(at -0.40005 0 90)
			(size 0 0)
			(layers "F.Cu" "F.Mask" "F.Paste")
			(net "PVCCIN_CPU1_VDD6")
		)
		(pad "2" smd circle
			(at 0.40005 0 90)
			(size 0 0)
			(layers "F.Cu" "F.Mask" "F.Paste")
			(net "GND")
		)
	)
)
